# T6G (Grand Teton) — schematic parts with pin connectivity, parts 4587–4599 of 8303; source: Cadence DE-HDL packaged netlist (pstxprt.dat, pstxnet.dat, pstchip.dat)

PU28  ISL99390FRZTR5935  ISL99390FRZ-TR5935 IC  pkg QFN21_6X5XB  page 212
  1  VOS  IN  = PVDDCR_CPU0_P1_VOS4
  2  AGND  POWER  = GND
  3  VCC  POWER  = PVDDCR_CPU0_P1_VCC4
  4  PVCC  POWER  = PVDDCR_CPU0_P1_PVCC
  5  PGND1  POWER  = GND
  6  GL1  OUT  = NC_PVDDCR_CPU0_P1_GL1_4
  7_9-20_24  PGND2  POWER  = GND
  10_19  SW  OUT  = SW_PVDDCR_CPU0_P1_SW4
  25_29  VIN1  IN  = SW_P12V_AUX_PVDDCR_CPU0_P1_FLT
  30  VIN2  IN  = SW_P12V_AUX_PVDDCR_CPU0_P1_FLT
  31  DNC  TRI  = NC_PVDDCR_CPU0_P1_DNC4
  32  PHASE  POWER  = SW_PVDDCR_CPU0_P1_PH4
  33  BOOT  POWER  = SW_PVDDCR_CPU0_P1_BOOT4
  34  PWM  IN  = PVDDCR_CPU0_P1_PWM4
  35  EN  IN  = PVDDCR_CPU0_P1_VCC4
  36  TOUT_FLT  OUT  = PVDDCR_CPU0_P1_TEMP0
  37  LSET  OUT  = PVDDCR_CPU0_P1_LSET4
  38  IOUT  OUT  = PVDDCR_CPU0_P1_IMON4
  39  REFIN  IN  = PVDDCR_CPU0_P1_VCCS
  40  PGND3  POWER  = GND
  41  GL2  OUT  = NC_PVDDCR_CPU0_P1_GL2_4

PU29  ISL99390FRZTR5935  ISL99390FRZ-TR5935 IC  pkg QFN21_6X5XB  page 213
  1  VOS  IN  = PVDDCR_CPU0_P1_VOS5
  2  AGND  POWER  = GND
  3  VCC  POWER  = PVDDCR_CPU0_P1_VCC5
  4  PVCC  POWER  = PVDDCR_CPU0_P1_PVCC
  5  PGND1  POWER  = GND
  6  GL1  OUT  = NC_PVDDCR_CPU0_P1_GL1_5
  7_9-20_24  PGND2  POWER  = GND
  10_19  SW  OUT  = SW_PVDDCR_CPU0_P1_SW5
  25_29  VIN1  IN  = SW_P12V_AUX_PVDDCR_CPU0_P1_FLT
  30  VIN2  IN  = SW_P12V_AUX_PVDDCR_CPU0_P1_FLT
  31  DNC  TRI  = NC_PVDDCR_CPU0_P1_DNC5
  32  PHASE  POWER  = SW_PVDDCR_CPU0_P1_PH5
  33  BOOT  POWER  = SW_PVDDCR_CPU0_P1_BOOT5
  34  PWM  IN  = PVDDCR_CPU0_P1_PWM5
  35  EN  IN  = PVDDCR_CPU0_P1_VCC5
  36  TOUT_FLT  OUT  = PVDDCR_CPU0_P1_TEMP0
  37  LSET  OUT  = PVDDCR_CPU0_P1_LSET5
  38  IOUT  OUT  = PVDDCR_CPU0_P1_IMON5
  39  REFIN  IN  = PVDDCR_CPU0_P1_VCCS
  40  PGND3  POWER  = GND
  41  GL2  OUT  = NC_PVDDCR_CPU0_P1_GL2_5

PU30  ISL99390FRZTR5935  ISL99390FRZ-TR5935 IC  pkg QFN21_6X5XB  page 215
  1  VOS  IN  = PVDDCR_SOC_P1_VOS1
  2  AGND  POWER  = GND
  3  VCC  POWER  = PVDDCR_SOC_P1_VCC1
  4  PVCC  POWER  = PVDDCR_CPU0_P1_PVCC
  5  PGND1  POWER  = GND
  6  GL1  OUT  = NC_PVDDCR_SOC_P1_GL1_1
  7_9-20_24  PGND2  POWER  = GND
  10_19  SW  OUT  = SW_PVDDCR_SOC_P1_SW1
  25_29  VIN1  IN  = SW_P12V_AUX_PVDDCR_SOC_P1_FLT
  30  VIN2  IN  = SW_P12V_AUX_PVDDCR_SOC_P1_FLT
  31  DNC  TRI  = NC_PVDDCR_SOC_P1_DNC1
  32  PHASE  POWER  = SW_PVDDCR_SOC_P1_PH1
  33  BOOT  POWER  = SW_PVDDCR_SOC_P1_BOOT1
  34  PWM  IN  = PVDDCR_SOC_P1_PWM1
  35  EN  IN  = PVDDCR_SOC_P1_VCC1
  36  TOUT_FLT  OUT  = PVDDCR_SOC_P1_TEMP1
  37  LSET  OUT  = PVDDCR_SOC_P1_LSET1
  38  IOUT  OUT  = PVDDCR_SOC_P1_IMON1
  39  REFIN  IN  = PVDDCR_CPU0_P1_VCCS
  40  PGND3  POWER  = GND
  41  GL2  OUT  = NC_PVDDCR_SOC_P1_GL2_1

PU31  ISL99390FRZTR5935  ISL99390FRZ-TR5935 IC  pkg QFN21_6X5XB  page 215
  1  VOS  IN  = PVDDCR_SOC_P1_VOS2
  2  AGND  POWER  = GND
  3  VCC  POWER  = PVDDCR_SOC_P1_VCC2
  4  PVCC  POWER  = PVDDCR_CPU0_P1_PVCC
  5  PGND1  POWER  = GND
  6  GL1  OUT  = NC_PVDDCR_SOC_P1_GL1_2
  7_9-20_24  PGND2  POWER  = GND
  10_19  SW  OUT  = SW_PVDDCR_SOC_P1_SW2
  25_29  VIN1  IN  = SW_P12V_AUX_PVDDCR_SOC_P1_FLT
  30  VIN2  IN  = SW_P12V_AUX_PVDDCR_SOC_P1_FLT
  31  DNC  TRI  = NC_PVDDCR_SOC_P1_DNC2
  32  PHASE  POWER  = SW_PVDDCR_SOC_P1_PH2
  33  BOOT  POWER  = SW_PVDDCR_SOC_P1_BOOT2
  34  PWM  IN  = PVDDCR_SOC_P1_PWM2
  35  EN  IN  = PVDDCR_SOC_P1_VCC2
  36  TOUT_FLT  OUT  = PVDDCR_SOC_P1_TEMP1
  37  LSET  OUT  = PVDDCR_SOC_P1_LSET2
  38  IOUT  OUT  = PVDDCR_SOC_P1_IMON2
  39  REFIN  IN  = PVDDCR_CPU0_P1_VCCS
  40  PGND3  POWER  = GND
  41  GL2  OUT  = NC_PVDDCR_SOC_P1_GL2_2

PU32  ISL99390FRZTR5935  ISL99390FRZ-TR5935 IC  pkg QFN21_6X5XB  page 216
  1  VOS  IN  = PVDDCR_SOC_P1_VOS3
  2  AGND  POWER  = GND
  3  VCC  POWER  = PVDDCR_SOC_P1_VCC3
  4  PVCC  POWER  = PVDDCR_CPU0_P1_PVCC
  5  PGND1  POWER  = GND
  6  GL1  OUT  = NC_PVDDCR_SOC_P1_GL1_3
  7_9-20_24  PGND2  POWER  = GND
  10_19  SW  OUT  = SW_PVDDCR_SOC_P1_SW3
  25_29  VIN1  IN  = SW_P12V_AUX_PVDDCR_SOC_P1_FLT
  30  VIN2  IN  = SW_P12V_AUX_PVDDCR_SOC_P1_FLT
  31  DNC  TRI  = NC_PVDDCR_SOC_P1_DNC3
  32  PHASE  POWER  = SW_PVDDCR_SOC_P1_PH3
  33  BOOT  POWER  = SW_PVDDCR_SOC_P1_BOOT3
  34  PWM  IN  = PVDDCR_SOC_P1_PWM3
  35  EN  IN  = PVDDCR_SOC_P1_VCC3
  36  TOUT_FLT  OUT  = PVDDCR_SOC_P1_TEMP1
  37  LSET  OUT  = PVDDCR_SOC_P1_LSET3
  38  IOUT  OUT  = PVDDCR_SOC_P1_IMON3
  39  REFIN  IN  = PVDDCR_CPU0_P1_VCCS
  40  PGND3  POWER  = GND
  41  GL2  OUT  = NC_PVDDCR_SOC_P1_GL2_3

PU33  ISL99390FRZTR5935  ISL99390FRZ-TR5935 IC  pkg QFN21_6X5XB  page 220
  1  VOS  IN  = PVDDCR_CPU1_P1_VOS6
  2  AGND  POWER  = GND
  3  VCC  POWER  = PVDDCR_CPU1_P1_VCC6
  4  PVCC  POWER  = PVDDCR_CPU1_P1_PVCC
  5  PGND1  POWER  = GND
  6  GL1  OUT  = NC_PVDDCR_CPU1_P1_GL1_6
  7_9-20_24  PGND2  POWER  = GND
  10_19  SW  OUT  = SW_PVDDCR_CPU1_P1_SW6
  25_29  VIN1  IN  = SW_P12V_AUX_PVDDCR_CPU1_P1_FLT
  30  VIN2  IN  = SW_P12V_AUX_PVDDCR_CPU1_P1_FLT
  31  DNC  TRI  = NC_PVDDCR_CPU1_P1_DNC6
  32  PHASE  POWER  = SW_PVDDCR_CPU1_P1_BOOTR6
  33  BOOT  POWER  = SW_PVDDCR_CPU1_P1_BOOT6
  34  PWM  IN  = PVDDCR_CPU1_P1_PWM6
  35  EN  IN  = PVDDCR_CPU1_P1_VCC6
  36  TOUT_FLT  OUT  = PVDDCR_CPU1_P1_TEMP0
  37  LSET  OUT  = PVDDCR_CPU1_P1_LSET6
  38  IOUT  OUT  = PVDDCR_CPU1_P1_IMON6
  39  REFIN  IN  = PVDDCR_CPU1_P1_VCCS
  40  PGND3  POWER  = GND
  41  GL2  OUT  = NC_PVDDCR_CPU1_P1_GL2_6

PU34  RAA229620GNPHA0  RAA229620GNP#HA0 IC  pkg QFN48_TH_0-4_6X6XH  page 217
  1  PWM0  OUT  = PVDDIO_P1_PWM1
  2  PWM1  OUT  = PVDDIO_P1_PWM2
  3  PWM2  OUT  = PVDDIO_P1_PWM3
  4  PWM3  OUT  = PVDDIO_P1_PWM4
  5  PWM4  OUT  = NC_PVDDCR_CPU1_P1_PWM8
  6  PWM5  OUT  = NC_PVDDCR_CPU1_P1_PWM7
  7  PWM6  OUT  = PVDDCR_CPU1_P1_PWM6
  8  PWM7  OUT  = PVDDCR_CPU1_P1_PWM5
  9  PWM8  OUT  = PVDDCR_CPU1_P1_PWM4
  10  PWM9  OUT  = PVDDCR_CPU1_P1_PWM3
  11  PWM10  OUT  = PVDDCR_CPU1_P1_PWM2
  12  PWM11  OUT  = PVDDCR_CPU1_P1_PWM1
  13  PMSDA  BI  = SMB_DIO_PVDDCR_CPU1_P1_R
  14  PMSCL  IN  = SMB_CLK_PVDDCR_CPU1_P1_R
  15  NPMALERT  OUT  = PVDDCR_CPU1_P1_SMB_ALERT_R
  16  PG0  OUT  = PWRGD_PVDDCR_CPU1_P1_R
  17  EN0  IN  = PVDDCR_CPU1_P1_EN_R
  18  RESET_L  IN  = PVDDCR_CPU1_P1_RESET_N_R
  19  VDDIO  POWER  = PVDD18_S5_P1
  20  PG1  OUT  = PWRGD_PVDDIO_P1_R
  21  SVD  IN  = SVID_PVDDCR_CPU1_P1_SVD_R1
  22  SVC  IN  = SVID_PVDDCR_CPU1_P1_SVC_R1
  23  SVTO  OUT  = SVID_PVDDCR_CPU1_P1_SVTO_R
  24  SVTI  IN  = SVID_PVDDCR_CPU1_P1_SVTI_R
  25  VSEN0  IN  = VSENSE_PVDDCR_CPU1_P1_VSEN0
  26  RGND0  IN  = VSENSE_VSS_SENSE_C_P1
  27  CS11  IN  = PVDDCR_CPU1_P1_IMON1
  28  CS10  IN  = PVDDCR_CPU1_P1_IMON2
  29  CS9  IN  = PVDDCR_CPU1_P1_IMON3
  30  CS8  IN  = PVDDCR_CPU1_P1_IMON4
  31  CS7  IN  = PVDDCR_CPU1_P1_IMON5
  32  CS6  IN  = PVDDCR_CPU1_P1_IMON6
  33  CS5  IN  = NC_PVDDCR_CPU1_P1_IMON7
  34  CS4  IN  = NC_PVDDCR_CPU1_P1_IMON8
  35  CS3  IN  = PVDDIO_P1_IMON4
  36  CS2  IN  = PVDDIO_P1_IMON3
  37  CS1  IN  = PVDDIO_P1_IMON2
  38  CS0  IN  = PVDDIO_P1_IMON1
  39  RGND1  IN  = VSENSE_VSS_SENSE_B_P1
  40  VSEN1  IN  = VSENSE_PVDDIO_P1_VSEN1
  41  OCP_L  OUT  = PVDDCR_CPU1_P1_OCP_N_R
  42  \en1||addr_cfg\  IN  = PVDDCR_CPU1_P1_EN1_ADDR_CFG
  43  TEMP1  IN  = PVDDIO_P1_TEMP1
  44  TEMP0  IN  = PVDDCR_CPU1_P1_TEMP0
  45  \vmon||iinsen\  BI  = PVDDCR_CPU1_P1_VMON
  46  VINSEN  IN  = PVDDCR_CPU1_P1_VINSEN
  47  VCC  POWER  = PVDDCR_CPU1_P1_VCC
  48  VCCS  POWER  = PVDDCR_CPU1_P1_VCCS
  TH  TH_GND  POWER  = GND

PU35  ISL99390FRZTR5935  ISL99390FRZ-TR5935 IC  pkg QFN21_6X5XB  page 218
  1  VOS  IN  = PVDDCR_CPU1_P1_VOS1
  2  AGND  POWER  = GND
  3  VCC  POWER  = PVDDCR_CPU1_P1_VCC1
  4  PVCC  POWER  = PVDDCR_CPU1_P1_PVCC
  5  PGND1  POWER  = GND
  6  GL1  OUT  = NC_PVDDCR_CPU1_P1_GL1_1
  7_9-20_24  PGND2  POWER  = GND
  10_19  SW  OUT  = SW_PVDDCR_CPU1_P1_SW1
  25_29  VIN1  IN  = SW_P12V_AUX_PVDDCR_CPU1_P1_FLT
  30  VIN2  IN  = SW_P12V_AUX_PVDDCR_CPU1_P1_FLT
  31  DNC  TRI  = NC_PVDDCR_CPU1_P1_DNC1
  32  PHASE  POWER  = SW_PVDDCR_CPU1_P1_BOOTR1
  33  BOOT  POWER  = SW_PVDDCR_CPU1_P1_BOOT1
  34  PWM  IN  = PVDDCR_CPU1_P1_PWM1
  35  EN  IN  = PVDDCR_CPU1_P1_VCC1
  36  TOUT_FLT  OUT  = PVDDCR_CPU1_P1_TEMP0
  37  LSET  OUT  = PVDDCR_CPU1_P1_LSET1
  38  IOUT  OUT  = PVDDCR_CPU1_P1_IMON1
  39  REFIN  IN  = PVDDCR_CPU1_P1_VCCS
  40  PGND3  POWER  = GND
  41  GL2  OUT  = NC_PVDDCR_CPU1_P1_GL2_1

PU36  ISL99390FRZTR5935  ISL99390FRZ-TR5935 IC  pkg QFN21_6X5XB  page 219
  1  VOS  IN  = PVDDCR_CPU1_P1_VOS4
  2  AGND  POWER  = GND
  3  VCC  POWER  = PVDDCR_CPU1_P1_VCC4
  4  PVCC  POWER  = PVDDCR_CPU1_P1_PVCC
  5  PGND1  POWER  = GND
  6  GL1  OUT  = NC_PVDDCR_CPU1_P1_GL1_4
  7_9-20_24  PGND2  POWER  = GND
  10_19  SW  OUT  = SW_PVDDCR_CPU1_P1_SW4
  25_29  VIN1  IN  = SW_P12V_AUX_PVDDCR_CPU1_P1_FLT
  30  VIN2  IN  = SW_P12V_AUX_PVDDCR_CPU1_P1_FLT
  31  DNC  TRI  = NC_PVDDCR_CPU1_P1_DNC4
  32  PHASE  POWER  = SW_PVDDCR_CPU1_P1_BOOTR4
  33  BOOT  POWER  = SW_PVDDCR_CPU1_P1_BOOT4
  34  PWM  IN  = PVDDCR_CPU1_P1_PWM4
  35  EN  IN  = PVDDCR_CPU1_P1_VCC4
  36  TOUT_FLT  OUT  = PVDDCR_CPU1_P1_TEMP0
  37  LSET  OUT  = PVDDCR_CPU1_P1_LSET4
  38  IOUT  OUT  = PVDDCR_CPU1_P1_IMON4
  39  REFIN  IN  = PVDDCR_CPU1_P1_VCCS
  40  PGND3  POWER  = GND
  41  GL2  OUT  = NC_PVDDCR_CPU1_P1_GL2_4

PU37  ISL99390FRZTR5935  ISL99390FRZ-TR5935 IC  pkg QFN21_6X5XB  page 219
  1  VOS  IN  = PVDDCR_CPU1_P1_VOS3
  2  AGND  POWER  = GND
  3  VCC  POWER  = PVDDCR_CPU1_P1_VCC3
  4  PVCC  POWER  = PVDDCR_CPU1_P1_PVCC
  5  PGND1  POWER  = GND
  6  GL1  OUT  = NC_PVDDCR_CPU1_P1_GL1_3
  7_9-20_24  PGND2  POWER  = GND
  10_19  SW  OUT  = SW_PVDDCR_CPU1_P1_SW3
  25_29  VIN1  IN  = SW_P12V_AUX_PVDDCR_CPU1_P1_FLT
  30  VIN2  IN  = SW_P12V_AUX_PVDDCR_CPU1_P1_FLT
  31  DNC  TRI  = NC_PVDDCR_CPU1_P1_DNC3
  32  PHASE  POWER  = SW_PVDDCR_CPU1_P1_BOOTR3
  33  BOOT  POWER  = SW_PVDDCR_CPU1_P1_BOOT3
  34  PWM  IN  = PVDDCR_CPU1_P1_PWM3
  35  EN  IN  = PVDDCR_CPU1_P1_VCC3
  36  TOUT_FLT  OUT  = PVDDCR_CPU1_P1_TEMP0
  37  LSET  OUT  = PVDDCR_CPU1_P1_LSET3
  38  IOUT  OUT  = PVDDCR_CPU1_P1_IMON3
  39  REFIN  IN  = PVDDCR_CPU1_P1_VCCS
  40  PGND3  POWER  = GND
  41  GL2  OUT  = NC_PVDDCR_CPU1_P1_GL2_3

PU38  ISL99390FRZTR5935  ISL99390FRZ-TR5935 IC  pkg QFN21_6X5XB  page 220
  1  VOS  IN  = PVDDCR_CPU1_P1_VOS5
  2  AGND  POWER  = GND
  3  VCC  POWER  = PVDDCR_CPU1_P1_VCC5
  4  PVCC  POWER  = PVDDCR_CPU1_P1_PVCC
  5  PGND1  POWER  = GND
  6  GL1  OUT  = NC_PVDDCR_CPU1_P1_GL1_5
  7_9-20_24  PGND2  POWER  = GND
  10_19  SW  OUT  = SW_PVDDCR_CPU1_P1_SW5
  25_29  VIN1  IN  = SW_P12V_AUX_PVDDCR_CPU1_P1_FLT
  30  VIN2  IN  = SW_P12V_AUX_PVDDCR_CPU1_P1_FLT
  31  DNC  TRI  = NC_PVDDCR_CPU1_P1_DNC5
  32  PHASE  POWER  = SW_PVDDCR_CPU1_P1_BOOTR5
  33  BOOT  POWER  = SW_PVDDCR_CPU1_P1_BOOT5
  34  PWM  IN  = PVDDCR_CPU1_P1_PWM5
  35  EN  IN  = PVDDCR_CPU1_P1_VCC5
  36  TOUT_FLT  OUT  = PVDDCR_CPU1_P1_TEMP0
  37  LSET  OUT  = PVDDCR_CPU1_P1_LSET5
  38  IOUT  OUT  = PVDDCR_CPU1_P1_IMON5
  39  REFIN  IN  = PVDDCR_CPU1_P1_VCCS
  40  PGND3  POWER  = GND
  41  GL2  OUT  = NC_PVDDCR_CPU1_P1_GL2_5

PU39  ISL99390FRZTR5935  ISL99390FRZ-TR5935 IC  pkg QFN21_6X5XB  page 222
  1  VOS  IN  = PVDDIO_P1_VOS1
  2  AGND  POWER  = GND
  3  VCC  POWER  = PVDDIO_P1_VCC1
  4  PVCC  POWER  = PVDDCR_CPU1_P1_PVCC
  5  PGND1  POWER  = GND
  6  GL1  OUT  = NC_PVDDIO_P1_GL1_1
  7_9-20_24  PGND2  POWER  = GND
  10_19  SW  OUT  = SW_PVDDIO_P1_SW1
  25_29  VIN1  IN  = SW_P12V_AUX_PVDDIO_P1_FLT
  30  VIN2  IN  = SW_P12V_AUX_PVDDIO_P1_FLT
  31  DNC  TRI  = NC_PVDDIO_P1_DNC1
  32  PHASE  POWER  = SW_PVDDIO_P1_BOOTR1
  33  BOOT  POWER  = SW_PVDDIO_P1_BOOT1
  34  PWM  IN  = PVDDIO_P1_PWM1
  35  EN  IN  = PVDDIO_P1_VCC1
  36  TOUT_FLT  OUT  = PVDDIO_P1_TEMP1
  37  LSET  OUT  = PVDDIO_P1_LSET1
  38  IOUT  OUT  = PVDDIO_P1_IMON1
  39  REFIN  IN  = PVDDCR_CPU1_P1_VCCS
  40  PGND3  POWER  = GND
  41  GL2  OUT  = NC_PVDDIO_P1_GL2_1

PU40  ISL99390FRZTR5935  ISL99390FRZ-TR5935 IC  pkg QFN21_6X5XB  page 222
  1  VOS  IN  = PVDDIO_P1_VOS2
  2  AGND  POWER  = GND
  3  VCC  POWER  = PVDDIO_P1_VCC2
  4  PVCC  POWER  = PVDDCR_CPU1_P1_PVCC
  5  PGND1  POWER  = GND
  6  GL1  OUT  = NC_PVDDIO_P1_GL1_2
  7_9-20_24  PGND2  POWER  = GND
  10_19  SW  OUT  = SW_PVDDIO_P1_SW2
  25_29  VIN1  IN  = SW_P12V_AUX_PVDDIO_P1_FLT
  30  VIN2  IN  = SW_P12V_AUX_PVDDIO_P1_FLT
  31  DNC  TRI  = NC_PVDDIO_P1_DNC2
  32  PHASE  POWER  = SW_PVDDIO_P1_BOOTR2
  33  BOOT  POWER  = SW_PVDDIO_P1_BOOT2
  34  PWM  IN  = PVDDIO_P1_PWM2
  35  EN  IN  = PVDDIO_P1_VCC2
  36  TOUT_FLT  OUT  = PVDDIO_P1_TEMP1
  37  LSET  OUT  = PVDDIO_P1_LSET2
  38  IOUT  OUT  = PVDDIO_P1_IMON2
  39  REFIN  IN  = PVDDCR_CPU1_P1_VCCS
  40  PGND3  POWER  = GND
  41  GL2  OUT  = NC_PVDDIO_P1_GL2_2
